(kicad_pcb
	(version 20260206)
	(generator "pcbnew")
	(generator_version "10.0")
	(general
		(thickness 1.6)
		(legacy_teardrops no)
	)
	(paper "A4")
	(title_block
		(title "03242023_DA0F0TMBIJ0_F0T_Motherboard_J_brd_V01_OCP.brd")
		(comment 1 "Grand Teton / footprint 3039 of 6105 (U2), pads 3679-3790 of 4677")
	)
	(layers
		(0 "F.Cu" signal "TOP")
		(4 "In1.Cu" signal "GND")
		(6 "In2.Cu" signal "IN1")
		(8 "In3.Cu" signal "GND1")
		(10 "In4.Cu" signal "IN2")
		(12 "In5.Cu" signal "GND2")
		(14 "In6.Cu" signal "IN3")
		(16 "In7.Cu" signal "GND3")
		(18 "In8.Cu" signal "VCC")
		(20 "In9.Cu" signal "VCC1")
		(22 "In10.Cu" signal "GND4")
		(24 "In11.Cu" signal "IN4")
		(26 "In12.Cu" signal "GND5")
		(28 "In13.Cu" signal "IN5")
		(30 "In14.Cu" signal "GND6")
		(32 "In15.Cu" signal "IN6")
		(34 "In16.Cu" signal "GND7")
		(2 "B.Cu" signal "BOTTOM")
		(9 "F.Adhes" user "F.Adhesive")
		(11 "B.Adhes" user "B.Adhesive")
		(13 "F.Paste" user "Package Geometry/Pastemask Top")
		(15 "B.Paste" user "Package Geometry/Pastemask Bottom")
		(5 "F.SilkS" user "Ref Des/Silkscreen Top")
		(7 "B.SilkS" user "Ref Des/Silkscreen Bottom")
		(1 "F.Mask" user "Board Geometry/Soldermask Top")
		(3 "B.Mask" user "Board Geometry/Soldermask Bottom")
		(17 "Dwgs.User" user "User.Drawings")
		(19 "Cmts.User" user "User.Comments")
		(21 "Eco1.User" user "User.Eco1")
		(23 "Eco2.User" user "User.Eco2")
		(25 "Edge.Cuts" user "Board Geometry/Outline")
		(27 "Margin" user)
		(31 "F.CrtYd" user "Package Geometry/Place Bound Top")
		(29 "B.CrtYd" user "Package Geometry/Place Bound Bottom")
		(35 "F.Fab" user "Ref Des/Assembly Top")
		(33 "B.Fab" user "Ref Des/Assembly Bottom")
	)
	(footprint ""
		(layer "F.Cu")
		(at 359.870248 -251.76988 90)
		(property "Reference" "U2"
			(at -74.416158 -44.488608 0)
			(unlocked yes)
			(layer "F.SilkS")
			(effects
				(font
					(size 1.6002 1.1938)
					(thickness 0.1524)
				)
				(justify left)
			)
		)
		(property "Value" ""
			(at 0 0 90)
			(layer "F.Fab")
			(effects
				(font
					(size 1.27 1.27)
				)
			)
		)
		(duplicate_pad_numbers_are_jumpers no)
		(pad "EH71" smd circle
			(at 21.147278 23.314914 270)
			(size 0.4318 0.4318)
			(layers "F.Cu" "F.Mask" "F.Paste")
			(net "M_E_CPU0_SA_DQ<11>")
		)
		(pad "EH73" smd circle
			(at 22.77491 23.314914 270)
			(size 0.4318 0.4318)
			(layers "F.Cu" "F.Mask" "F.Paste")
			(net "GND")
		)
		(pad "EH75" smd circle
			(at 24.402796 23.314914 270)
			(size 0.4318 0.4318)
			(layers "F.Cu" "F.Mask" "F.Paste")
			(net "M_F_CPU0_SA_DQ<6>")
		)
		(pad "EH77" smd circle
			(at 26.030682 23.314914 270)
			(size 0.4318 0.4318)
			(layers "F.Cu" "F.Mask" "F.Paste")
			(net "M_F_CPU0_SA_DQ<1>")
		)
		(pad "EH79" smd circle
			(at 27.658314 23.314914 270)
			(size 0.4318 0.4318)
			(layers "F.Cu" "F.Mask" "F.Paste")
			(net "GND")
		)
		(pad "EH81" smd circle
			(at 29.2862 23.314914 270)
			(size 0.4318 0.4318)
			(layers "F.Cu" "F.Mask" "F.Paste")
			(net "GND")
		)
		(pad "EH83" smd circle
			(at 30.914086 23.314914 270)
			(size 0.4318 0.4318)
			(layers "F.Cu" "F.Mask" "F.Paste")
			(net "GND")
		)
		(pad "EH85" smd circle
			(at 32.541718 23.314914 270)
			(size 0.4318 0.4318)
			(layers "F.Cu" "F.Mask" "F.Paste")
			(net "Net_701")
		)
		(pad "EH87" smd circle
			(at 34.169604 23.314914 270)
			(size 0.4318 0.4318)
			(layers "F.Cu" "F.Mask" "F.Paste")
			(net "Net_659")
		)
		(pad "EH89" smd oval
			(at 35.797236 23.314914 315)
			(size 0.381 0.4826)
			(drill
				(offset 0 -0.0508)
			)
			(layers "F.Cu" "F.Mask" "F.Paste")
			(net "P5E_CPU0_PE3_RX_DN<0>")
		)
		(pad "EJ3" smd oval
			(at -35.797236 23.675086 225)
			(size 0.381 0.4826)
			(drill
				(offset 0 -0.0508)
			)
			(layers "F.Cu" "F.Mask" "F.Paste")
			(net "UPI_CPU1_CPU0_P0P1_DP<0>")
		)
		(pad "EJ5" smd circle
			(at -34.169604 23.675086 270)
			(size 0.4318 0.4318)
			(layers "F.Cu" "F.Mask" "F.Paste")
			(net "M_G_CPU0_SB_DQ<29>")
		)
		(pad "EJ7" smd circle
			(at -32.541718 23.675086 270)
			(size 0.4318 0.4318)
			(layers "F.Cu" "F.Mask" "F.Paste")
			(net "GND")
		)
		(pad "EJ9" smd circle
			(at -30.914086 23.675086 270)
			(size 0.4318 0.4318)
			(layers "F.Cu" "F.Mask" "F.Paste")
			(net "GND")
		)
		(pad "EJ11" smd circle
			(at -29.2862 23.675086 270)
			(size 0.4318 0.4318)
			(layers "F.Cu" "F.Mask" "F.Paste")
			(net "GND")
		)
		(pad "EJ13" smd circle
			(at -27.658314 23.675086 270)
			(size 0.4318 0.4318)
			(layers "F.Cu" "F.Mask" "F.Paste")
			(net "GND")
		)
		(pad "EJ15" smd circle
			(at -26.030682 23.675086 270)
			(size 0.4318 0.4318)
			(layers "F.Cu" "F.Mask" "F.Paste")
			(net "PVCCFA_EHV_FIVRA_CPU0")
		)
		(pad "EJ17" smd circle
			(at -24.402796 23.675086 270)
			(size 0.4318 0.4318)
			(layers "F.Cu" "F.Mask" "F.Paste")
			(net "GND")
		)
		(pad "EJ19" smd circle
			(at -22.77491 23.675086 270)
			(size 0.4318 0.4318)
			(layers "F.Cu" "F.Mask" "F.Paste")
			(net "GND")
		)
		(pad "EJ21" smd circle
			(at -21.147278 23.675086 270)
			(size 0.4318 0.4318)
			(layers "F.Cu" "F.Mask" "F.Paste")
			(net "M_F_CPU0_SB_DQS_DN<6>")
		)
		(pad "EJ23" smd circle
			(at -19.519392 23.675086 270)
			(size 0.4318 0.4318)
			(layers "F.Cu" "F.Mask" "F.Paste")
			(net "GND")
		)
		(pad "EJ25" smd circle
			(at -17.89176 23.675086 270)
			(size 0.4318 0.4318)
			(layers "F.Cu" "F.Mask" "F.Paste")
			(net "GND")
		)
		(pad "EJ27" smd circle
			(at -16.263874 23.675086 270)
			(size 0.4318 0.4318)
			(layers "F.Cu" "F.Mask" "F.Paste")
			(net "M_E_CPU0_SB_DQS_DN<5>")
		)
		(pad "EJ29" smd circle
			(at -14.635988 23.675086 270)
			(size 0.4318 0.4318)
			(layers "F.Cu" "F.Mask" "F.Paste")
			(net "GND")
		)
		(pad "EJ31" smd circle
			(at -13.008356 23.675086 270)
			(size 0.4318 0.4318)
			(layers "F.Cu" "F.Mask" "F.Paste")
			(net "GND")
		)
		(pad "EJ33" smd circle
			(at -11.380724 23.675086 270)
			(size 0.4318 0.4318)
			(layers "F.Cu" "F.Mask" "F.Paste")
			(net "M_F_CPU0_SB_DQS_DN<4>")
		)
		(pad "EJ35" smd circle
			(at -9.752838 23.675086 270)
			(size 0.4318 0.4318)
			(layers "F.Cu" "F.Mask" "F.Paste")
			(net "GND")
		)
		(pad "EJ37" smd circle
			(at -8.124952 23.675086 270)
			(size 0.4318 0.4318)
			(layers "F.Cu" "F.Mask" "F.Paste")
			(net "GND")
		)
		(pad "EJ39" smd circle
			(at -6.49732 23.675086 270)
			(size 0.4318 0.4318)
			(layers "F.Cu" "F.Mask" "F.Paste")
			(net "M_F_CPU0_SB_PAR")
		)
		(pad "EJ41" smd circle
			(at -4.869434 23.675086 270)
			(size 0.4318 0.4318)
			(layers "F.Cu" "F.Mask" "F.Paste")
			(net "GND")
		)
		(pad "EJ43" smd circle
			(at -3.241802 23.675086 270)
			(size 0.4318 0.4318)
			(layers "F.Cu" "F.Mask" "F.Paste")
			(net "GND")
		)
		(pad "EJ45" smd circle
			(at -1.613916 23.675086 270)
			(size 0.4318 0.4318)
			(layers "F.Cu" "F.Mask" "F.Paste")
			(net "M_E_CPU0_CLK_DN<0>")
		)
		(pad "EJ48" smd circle
			(at 2.427732 23.784814 270)
			(size 0.4318 0.4318)
			(layers "F.Cu" "F.Mask" "F.Paste")
			(net "GND")
		)
		(pad "EJ50" smd circle
			(at 4.055618 23.784814 270)
			(size 0.4318 0.4318)
			(layers "F.Cu" "F.Mask" "F.Paste")
			(net "GND")
		)
		(pad "EJ52" smd circle
			(at 5.68325 23.784814 270)
			(size 0.4318 0.4318)
			(layers "F.Cu" "F.Mask" "F.Paste")
			(net "M_F_CPU0_SA_CA<1>")
		)
		(pad "EJ54" smd circle
			(at 7.311136 23.784814 270)
			(size 0.4318 0.4318)
			(layers "F.Cu" "F.Mask" "F.Paste")
			(net "GND")
		)
		(pad "EJ56" smd circle
			(at 8.939022 23.784814 270)
			(size 0.4318 0.4318)
			(layers "F.Cu" "F.Mask" "F.Paste")
			(net "GND")
		)
		(pad "EJ58" smd circle
			(at 10.566654 23.784814 270)
			(size 0.4318 0.4318)
			(layers "F.Cu" "F.Mask" "F.Paste")
			(net "M_F_CPU0_SA_DQS_DN<9>")
		)
		(pad "EJ60" smd circle
			(at 12.19454 23.784814 270)
			(size 0.4318 0.4318)
			(layers "F.Cu" "F.Mask" "F.Paste")
			(net "GND")
		)
		(pad "EJ62" smd circle
			(at 13.822426 23.784814 270)
			(size 0.4318 0.4318)
			(layers "F.Cu" "F.Mask" "F.Paste")
			(net "GND")
		)
		(pad "EJ64" smd circle
			(at 15.450058 23.784814 270)
			(size 0.4318 0.4318)
			(layers "F.Cu" "F.Mask" "F.Paste")
			(net "M_F_CPU0_SA_DQS_DN<7>")
		)
		(pad "EJ66" smd circle
			(at 17.07769 23.784814 270)
			(size 0.4318 0.4318)
			(layers "F.Cu" "F.Mask" "F.Paste")
			(net "GND")
		)
		(pad "EJ68" smd circle
			(at 18.705576 23.784814 270)
			(size 0.4318 0.4318)
			(layers "F.Cu" "F.Mask" "F.Paste")
			(net "GND")
		)
		(pad "EJ70" smd circle
			(at 20.333462 23.784814 270)
			(size 0.4318 0.4318)
			(layers "F.Cu" "F.Mask" "F.Paste")
			(net "M_E_CPU0_SA_DQS_DN<6>")
		)
		(pad "EJ72" smd circle
			(at 21.961094 23.784814 270)
			(size 0.4318 0.4318)
			(layers "F.Cu" "F.Mask" "F.Paste")
			(net "GND")
		)
		(pad "EJ74" smd circle
			(at 23.58898 23.784814 270)
			(size 0.4318 0.4318)
			(layers "F.Cu" "F.Mask" "F.Paste")
			(net "GND")
		)
		(pad "EJ76" smd circle
			(at 25.216612 23.784814 270)
			(size 0.4318 0.4318)
			(layers "F.Cu" "F.Mask" "F.Paste")
			(net "M_F_CPU0_SA_DQS_DN<5>")
		)
		(pad "EJ78" smd circle
			(at 26.844498 23.784814 270)
			(size 0.4318 0.4318)
			(layers "F.Cu" "F.Mask" "F.Paste")
			(net "GND")
		)
		(pad "EJ80" smd circle
			(at 28.472384 23.784814 270)
			(size 0.4318 0.4318)
			(layers "F.Cu" "F.Mask" "F.Paste")
			(net "GND")
		)
		(pad "EJ82" smd circle
			(at 30.100016 23.784814 270)
			(size 0.4318 0.4318)
			(layers "F.Cu" "F.Mask" "F.Paste")
			(net "GND")
		)
		(pad "EJ84" smd circle
			(at 31.727902 23.784814 270)
			(size 0.4318 0.4318)
			(layers "F.Cu" "F.Mask" "F.Paste")
			(net "PVCCFA_EHV_FIVRA_CPU0")
		)
		(pad "EJ86" smd circle
			(at 33.355534 23.784814 270)
			(size 0.4318 0.4318)
			(layers "F.Cu" "F.Mask" "F.Paste")
			(net "Net_683")
		)
		(pad "EJ88" smd oval
			(at 34.98342 23.784814 315)
			(size 0.381 0.4826)
			(drill
				(offset 0 -0.0508)
			)
			(layers "F.Cu" "F.Mask" "F.Paste")
			(net "GND")
		)
		(pad "EJ90" smd oval
			(at 36.611306 23.784814 315)
			(size 0.381 0.4826)
			(drill
				(offset 0 -0.0508)
			)
			(layers "F.Cu" "F.Mask" "F.Paste")
			(net "P5E_CPU0_PE3_RX_DP<0>")
		)
		(pad "EK2" smd oval
			(at -36.611306 24.144986 225)
			(size 0.381 0.4826)
			(drill
				(offset 0 -0.0508)
			)
			(layers "F.Cu" "F.Mask" "F.Paste")
			(net "GND")
		)
		(pad "EK4" smd oval
			(at -34.98342 24.144986 225)
			(size 0.381 0.4826)
			(drill
				(offset 0 -0.0508)
			)
			(layers "F.Cu" "F.Mask" "F.Paste")
			(net "GND")
		)
		(pad "EK6" smd circle
			(at -33.355534 24.144986 270)
			(size 0.4318 0.4318)
			(layers "F.Cu" "F.Mask" "F.Paste")
			(net "M_G_CPU0_SB_DQ<28>")
		)
		(pad "EK8" smd circle
			(at -31.727902 24.144986 270)
			(size 0.4318 0.4318)
			(layers "F.Cu" "F.Mask" "F.Paste")
			(net "M_G_CPU0_SB_DQ<24>")
		)
		(pad "EK10" smd circle
			(at -30.100016 24.144986 270)
			(size 0.4318 0.4318)
			(layers "F.Cu" "F.Mask" "F.Paste")
			(net "GND")
		)
		(pad "EK12" smd circle
			(at -28.472384 24.144986 270)
			(size 0.4318 0.4318)
			(layers "F.Cu" "F.Mask" "F.Paste")
			(net "M_F_CPU0_SB_DQS_DP<2>")
		)
		(pad "EK14" smd circle
			(at -26.844498 24.144986 270)
			(size 0.4318 0.4318)
			(layers "F.Cu" "F.Mask" "F.Paste")
			(net "GND")
		)
		(pad "EK16" smd circle
			(at -25.216612 24.144986 270)
			(size 0.4318 0.4318)
			(layers "F.Cu" "F.Mask" "F.Paste")
			(net "GND")
		)
		(pad "EK18" smd circle
			(at -23.58898 24.144986 270)
			(size 0.4318 0.4318)
			(layers "F.Cu" "F.Mask" "F.Paste")
			(net "M_E_CPU0_SB_DQS_DN<3>")
		)
		(pad "EK20" smd circle
			(at -21.961094 24.144986 270)
			(size 0.4318 0.4318)
			(layers "F.Cu" "F.Mask" "F.Paste")
			(net "GND")
		)
		(pad "EK22" smd circle
			(at -20.333462 24.144986 270)
			(size 0.4318 0.4318)
			(layers "F.Cu" "F.Mask" "F.Paste")
			(net "GND")
		)
		(pad "EK24" smd circle
			(at -18.705576 24.144986 270)
			(size 0.4318 0.4318)
			(layers "F.Cu" "F.Mask" "F.Paste")
			(net "M_E_CPU0_SB_DQS_DN<2>")
		)
		(pad "EK26" smd circle
			(at -17.07769 24.144986 270)
			(size 0.4318 0.4318)
			(layers "F.Cu" "F.Mask" "F.Paste")
			(net "GND")
		)
		(pad "EK28" smd circle
			(at -15.450058 24.144986 270)
			(size 0.4318 0.4318)
			(layers "F.Cu" "F.Mask" "F.Paste")
			(net "GND")
		)
		(pad "EK30" smd circle
			(at -13.822426 24.144986 270)
			(size 0.4318 0.4318)
			(layers "F.Cu" "F.Mask" "F.Paste")
			(net "M_E_CPU0_SB_DQS_DN<1>")
		)
		(pad "EK32" smd circle
			(at -12.19454 24.144986 270)
			(size 0.4318 0.4318)
			(layers "F.Cu" "F.Mask" "F.Paste")
			(net "GND")
		)
		(pad "EK34" smd circle
			(at -10.566654 24.144986 270)
			(size 0.4318 0.4318)
			(layers "F.Cu" "F.Mask" "F.Paste")
			(net "GND")
		)
		(pad "EK36" smd circle
			(at -8.939022 24.144986 270)
			(size 0.4318 0.4318)
			(layers "F.Cu" "F.Mask" "F.Paste")
			(net "M_E_CPU0_SB_DQS_DN<9>")
		)
		(pad "EK38" smd circle
			(at -7.311136 24.144986 270)
			(size 0.4318 0.4318)
			(layers "F.Cu" "F.Mask" "F.Paste")
			(net "GND")
		)
		(pad "EK40" smd circle
			(at -5.68325 24.144986 270)
			(size 0.4318 0.4318)
			(layers "F.Cu" "F.Mask" "F.Paste")
			(net "GND")
		)
		(pad "EK42" smd circle
			(at -4.055618 24.144986 270)
			(size 0.4318 0.4318)
			(layers "F.Cu" "F.Mask" "F.Paste")
			(net "M_E_CPU0_SB_CA<6>")
		)
		(pad "EK44" smd circle
			(at -2.427732 24.144986 270)
			(size 0.4318 0.4318)
			(layers "F.Cu" "F.Mask" "F.Paste")
			(net "GND")
		)
		(pad "EK47" smd circle
			(at 1.613916 24.254714 270)
			(size 0.4318 0.4318)
			(layers "F.Cu" "F.Mask" "F.Paste")
			(net "GND")
		)
		(pad "EK49" smd circle
			(at 3.241802 24.254714 270)
			(size 0.4318 0.4318)
			(layers "F.Cu" "F.Mask" "F.Paste")
			(net "M_E_CPU0_SA_CA<2>")
		)
		(pad "EK51" smd circle
			(at 4.869434 24.254714 270)
			(size 0.4318 0.4318)
			(layers "F.Cu" "F.Mask" "F.Paste")
			(net "GND")
		)
		(pad "EK53" smd circle
			(at 6.49732 24.254714 270)
			(size 0.4318 0.4318)
			(layers "F.Cu" "F.Mask" "F.Paste")
			(net "GND")
		)
		(pad "EK55" smd circle
			(at 8.124952 24.254714 270)
			(size 0.4318 0.4318)
			(layers "F.Cu" "F.Mask" "F.Paste")
			(net "M_E_CPU0_SA_DQS_DP<4>")
		)
		(pad "EK57" smd circle
			(at 9.752838 24.254714 270)
			(size 0.4318 0.4318)
			(layers "F.Cu" "F.Mask" "F.Paste")
			(net "GND")
		)
		(pad "EK59" smd circle
			(at 11.380724 24.254714 270)
			(size 0.4318 0.4318)
			(layers "F.Cu" "F.Mask" "F.Paste")
			(net "GND")
		)
		(pad "EK61" smd circle
			(at 13.008356 24.254714 270)
			(size 0.4318 0.4318)
			(layers "F.Cu" "F.Mask" "F.Paste")
			(net "M_E_CPU0_SA_DQS_DN<3>")
		)
		(pad "EK63" smd circle
			(at 14.635988 24.254714 270)
			(size 0.4318 0.4318)
			(layers "F.Cu" "F.Mask" "F.Paste")
			(net "GND")
		)
		(pad "EK65" smd circle
			(at 16.263874 24.254714 270)
			(size 0.4318 0.4318)
			(layers "F.Cu" "F.Mask" "F.Paste")
			(net "GND")
		)
		(pad "EK67" smd circle
			(at 17.89176 24.254714 270)
			(size 0.4318 0.4318)
			(layers "F.Cu" "F.Mask" "F.Paste")
			(net "M_E_CPU0_SA_DQS_DN<2>")
		)
		(pad "EK69" smd circle
			(at 19.519392 24.254714 270)
			(size 0.4318 0.4318)
			(layers "F.Cu" "F.Mask" "F.Paste")
			(net "GND")
		)
		(pad "EK71" smd circle
			(at 21.147278 24.254714 270)
			(size 0.4318 0.4318)
			(layers "F.Cu" "F.Mask" "F.Paste")
			(net "GND")
		)
		(pad "EK73" smd circle
			(at 22.77491 24.254714 270)
			(size 0.4318 0.4318)
			(layers "F.Cu" "F.Mask" "F.Paste")
			(net "M_E_CPU0_SA_DQ<5>")
		)
		(pad "EK75" smd circle
			(at 24.402796 24.254714 270)
			(size 0.4318 0.4318)
			(layers "F.Cu" "F.Mask" "F.Paste")
			(net "GND")
		)
		(pad "EK77" smd circle
			(at 26.030682 24.254714 270)
			(size 0.4318 0.4318)
			(layers "F.Cu" "F.Mask" "F.Paste")
			(net "GND")
		)
		(pad "EK79" smd circle
			(at 27.658314 24.254714 270)
			(size 0.4318 0.4318)
			(layers "F.Cu" "F.Mask" "F.Paste")
			(net "GND")
		)
		(pad "EK81" smd circle
			(at 29.2862 24.254714 270)
			(size 0.4318 0.4318)
			(layers "F.Cu" "F.Mask" "F.Paste")
			(net "GND")
		)
		(pad "EK83" smd circle
			(at 30.914086 24.254714 270)
			(size 0.4318 0.4318)
			(layers "F.Cu" "F.Mask" "F.Paste")
			(net "GND")
		)
		(pad "EK85" smd circle
			(at 32.541718 24.254714 270)
			(size 0.4318 0.4318)
			(layers "F.Cu" "F.Mask" "F.Paste")
			(net "Net_677")
		)
		(pad "EK87" smd oval
			(at 34.169604 24.254714 315)
			(size 0.381 0.4826)
			(drill
				(offset 0 -0.0508)
			)
			(layers "F.Cu" "F.Mask" "F.Paste")
			(net "Net_682")
		)
		(pad "EK89" smd oval
			(at 35.797236 24.254714 315)
			(size 0.381 0.4826)
			(drill
				(offset 0 -0.0508)
			)
			(layers "F.Cu" "F.Mask" "F.Paste")
			(net "GND")
		)
		(pad "EL3" smd oval
			(at -35.797236 24.614886 225)
			(size 0.381 0.4826)
			(drill
				(offset 0 -0.0508)
			)
			(layers "F.Cu" "F.Mask" "F.Paste")
			(net "GND")
		)
		(pad "EL5" smd oval
			(at -34.169604 24.614886 225)
			(size 0.381 0.4826)
			(drill
				(offset 0 -0.0508)
			)
			(layers "F.Cu" "F.Mask" "F.Paste")
			(net "GND")
		)
		(pad "EL7" smd circle
			(at -32.541718 24.614886 270)
			(size 0.4318 0.4318)
			(layers "F.Cu" "F.Mask" "F.Paste")
			(net "GND")
		)
		(pad "EL9" smd circle
			(at -30.914086 24.614886 270)
			(size 0.4318 0.4318)
			(layers "F.Cu" "F.Mask" "F.Paste")
			(net "GND")
		)
		(pad "EL11" smd circle
			(at -29.2862 24.614886 270)
			(size 0.4318 0.4318)
			(layers "F.Cu" "F.Mask" "F.Paste")
			(net "M_F_CPU0_SB_DQ<20>")
		)
		(pad "EL13" smd circle
			(at -27.658314 24.614886 270)
			(size 0.4318 0.4318)
			(layers "F.Cu" "F.Mask" "F.Paste")
			(net "M_F_CPU0_SB_DQ<17>")
		)
		(pad "EL15" smd circle
			(at -26.030682 24.614886 270)
			(size 0.4318 0.4318)
			(layers "F.Cu" "F.Mask" "F.Paste")
			(net "GND")
		)
		(pad "EL17" smd circle
			(at -24.402796 24.614886 270)
			(size 0.4318 0.4318)
			(layers "F.Cu" "F.Mask" "F.Paste")
			(net "M_E_CPU0_SB_DQ<28>")
		)
		(pad "EL19" smd circle
			(at -22.77491 24.614886 270)
			(size 0.4318 0.4318)
			(layers "F.Cu" "F.Mask" "F.Paste")
			(net "M_E_CPU0_SB_DQ<25>")
		)
		(pad "EL21" smd circle
			(at -21.147278 24.614886 270)
			(size 0.4318 0.4318)
			(layers "F.Cu" "F.Mask" "F.Paste")
			(net "GND")
		)
		(pad "EL23" smd circle
			(at -19.519392 24.614886 270)
			(size 0.4318 0.4318)
			(layers "F.Cu" "F.Mask" "F.Paste")
			(net "M_E_CPU0_SB_DQ<20>")
		)
		(pad "EL25" smd circle
			(at -17.89176 24.614886 270)
			(size 0.4318 0.4318)
			(layers "F.Cu" "F.Mask" "F.Paste")
			(net "M_E_CPU0_SB_DQ<17>")
		)
		(pad "EL27" smd circle
			(at -16.263874 24.614886 270)
			(size 0.4318 0.4318)
			(layers "F.Cu" "F.Mask" "F.Paste")
			(net "GND")
		)
		(pad "EL29" smd circle
			(at -14.635988 24.614886 270)
			(size 0.4318 0.4318)
			(layers "F.Cu" "F.Mask" "F.Paste")
			(net "M_E_CPU0_SB_DQ<12>")
		)
	)
)
